(kicad_pcb
	(version 20260206)
	(generator "pcbnew")
	(generator_version "10.0")
	(general
		(thickness 1.6)
		(legacy_teardrops no)
	)
	(paper "A4")
	(title_block
		(title "01162023_DA0F0TEBIF0_F0T_Expander_BD_F_brd_V02_OCP.brd")
		(comment 1 "Grand Teton / footprints 7287-7295 of 9728")
	)
	(layers
		(0 "F.Cu" signal "TOP")
		(4 "In1.Cu" signal "GND")
		(6 "In2.Cu" signal "VCC")
		(8 "In3.Cu" signal "VCC1")
		(10 "In4.Cu" signal "GND1")
		(12 "In5.Cu" signal "IN1")
		(14 "In6.Cu" signal "GND2")
		(16 "In7.Cu" signal "IN2")
		(18 "In8.Cu" signal "GND3")
		(20 "In9.Cu" signal "IN3")
		(22 "In10.Cu" signal "GND4")
		(24 "In11.Cu" signal "IN4")
		(26 "In12.Cu" signal "GND5")
		(28 "In13.Cu" signal "IN5")
		(30 "In14.Cu" signal "GND6")
		(32 "In15.Cu" signal "IN6")
		(34 "In16.Cu" signal "GND7")
		(2 "B.Cu" signal "BOTTOM")
		(9 "F.Adhes" user "F.Adhesive")
		(11 "B.Adhes" user "B.Adhesive")
		(13 "F.Paste" user "Package Geometry/Pastemask Top")
		(15 "B.Paste" user "Package Geometry/Pastemask Bottom")
		(5 "F.SilkS" user "Ref Des/Silkscreen Top")
		(7 "B.SilkS" user "Ref Des/Silkscreen Bottom")
		(1 "F.Mask" user "Board Geometry/Soldermask Top")
		(3 "B.Mask" user "Board Geometry/Soldermask Bottom")
		(17 "Dwgs.User" user "User.Drawings")
		(19 "Cmts.User" user "User.Comments")
		(21 "Eco1.User" user "User.Eco1")
		(23 "Eco2.User" user "User.Eco2")
		(25 "Edge.Cuts" user "Board Geometry/Outline")
		(27 "Margin" user)
		(31 "F.CrtYd" user "Package Geometry/Place Bound Top")
		(29 "B.CrtYd" user "Package Geometry/Place Bound Bottom")
		(35 "F.Fab" user "Ref Des/Assembly Top")
		(33 "B.Fab" user "Ref Des/Assembly Bottom")
	)
	(footprint ""
		(layer "B.Cu")
		(at 118.456964 -316.003686)
		(property "Reference" "C4266"
			(at 0 0 0)
			(layer "B.SilkS")
			(hide yes)
			(effects
				(font
					(size 1.27 1.27)
				)
				(justify mirror)
			)
		)
		(property "Value" ""
			(at 0 0 0)
			(layer "B.Fab")
			(effects
				(font
					(size 1.27 1.27)
				)
				(justify mirror)
			)
		)
		(duplicate_pad_numbers_are_jumpers no)
		(fp_line
			(start -0.299974 -0.150114)
			(end -0.299974 0.150114)
			(stroke
				(width 0.1)
				(type default)
			)
			(layer "B.Fab")
		)
		(fp_line
			(start -0.299974 0.150114)
			(end 0.299974 0.150114)
			(stroke
				(width 0.1)
				(type default)
			)
			(layer "B.Fab")
		)
		(fp_line
			(start 0.299974 -0.150114)
			(end -0.299974 -0.150114)
			(stroke
				(width 0.1)
				(type default)
			)
			(layer "B.Fab")
		)
		(fp_line
			(start 0.299974 0.150114)
			(end 0.299974 -0.150114)
			(stroke
				(width 0.1)
				(type default)
			)
			(layer "B.Fab")
		)
		(pad "1" smd rect
			(at 0.2667 0 180)
			(size 0.3048 0.381)
			(layers "B.Cu" "B.Mask" "B.Paste")
			(net "P0V8_SERDES_VDDA_PEX1")
		)
		(pad "2" smd rect
			(at -0.2667 0 180)
			(size 0.3048 0.381)
			(layers "B.Cu" "B.Mask" "B.Paste")
			(net "GND")
		)
	)
	(footprint ""
		(layer "B.Cu")
		(at 412.224982 -297.79976 90)
		(property "Reference" "C1913"
			(at 0 0 90)
			(layer "B.SilkS")
			(hide yes)
			(effects
				(font
					(size 1.27 1.27)
				)
				(justify mirror)
			)
		)
		(property "Value" ""
			(at 0 0 90)
			(layer "B.Fab")
			(effects
				(font
					(size 1.27 1.27)
				)
				(justify mirror)
			)
		)
		(duplicate_pad_numbers_are_jumpers no)
		(fp_line
			(start 0.299974 -0.150114)
			(end -0.299974 -0.150114)
			(stroke
				(width 0.1)
				(type default)
			)
			(layer "B.Fab")
		)
		(fp_line
			(start -0.299974 -0.150114)
			(end -0.299974 0.150114)
			(stroke
				(width 0.1)
				(type default)
			)
			(layer "B.Fab")
		)
		(fp_line
			(start 0.299974 0.150114)
			(end 0.299974 -0.150114)
			(stroke
				(width 0.1)
				(type default)
			)
			(layer "B.Fab")
		)
		(fp_line
			(start -0.299974 0.150114)
			(end 0.299974 0.150114)
			(stroke
				(width 0.1)
				(type default)
			)
			(layer "B.Fab")
		)
		(pad "1" smd rect
			(at 0.2667 0 270)
			(size 0.3048 0.381)
			(layers "B.Cu" "B.Mask" "B.Paste")
			(net "P0V8_PEX3")
		)
		(pad "2" smd rect
			(at -0.2667 0 270)
			(size 0.3048 0.381)
			(layers "B.Cu" "B.Mask" "B.Paste")
			(net "GND")
		)
	)
	(footprint ""
		(layer "B.Cu")
		(at 53.045614 -296.37482)
		(property "Reference" "C1111"
			(at 0 0 0)
			(layer "B.SilkS")
			(hide yes)
			(effects
				(font
					(size 1.27 1.27)
				)
				(justify mirror)
			)
		)
		(property "Value" ""
			(at 0 0 0)
			(layer "B.Fab")
			(effects
				(font
					(size 1.27 1.27)
				)
				(justify mirror)
			)
		)
		(duplicate_pad_numbers_are_jumpers no)
		(fp_line
			(start -0.299974 -0.150114)
			(end -0.299974 0.150114)
			(stroke
				(width 0.1)
				(type default)
			)
			(layer "B.Fab")
		)
		(fp_line
			(start -0.299974 0.150114)
			(end 0.299974 0.150114)
			(stroke
				(width 0.1)
				(type default)
			)
			(layer "B.Fab")
		)
		(fp_line
			(start 0.299974 -0.150114)
			(end -0.299974 -0.150114)
			(stroke
				(width 0.1)
				(type default)
			)
			(layer "B.Fab")
		)
		(fp_line
			(start 0.299974 0.150114)
			(end 0.299974 -0.150114)
			(stroke
				(width 0.1)
				(type default)
			)
			(layer "B.Fab")
		)
		(pad "1" smd rect
			(at 0.2667 0 180)
			(size 0.3048 0.381)
			(layers "B.Cu" "B.Mask" "B.Paste")
			(net "P0V8_PEX0")
		)
		(pad "2" smd rect
			(at -0.2667 0 180)
			(size 0.3048 0.381)
			(layers "B.Cu" "B.Mask" "B.Paste")
			(net "GND")
		)
	)
	(footprint ""
		(layer "B.Cu")
		(at 127.559308 -308.580028 90)
		(property "Reference" "C4262"
			(at 0 0 90)
			(layer "B.SilkS")
			(hide yes)
			(effects
				(font
					(size 1.27 1.27)
				)
				(justify mirror)
			)
		)
		(property "Value" ""
			(at 0 0 90)
			(layer "B.Fab")
			(effects
				(font
					(size 1.27 1.27)
				)
				(justify mirror)
			)
		)
		(duplicate_pad_numbers_are_jumpers no)
		(fp_line
			(start 1.2954 -0.5842)
			(end -1.2954 -0.5842)
			(stroke
				(width 0.1524)
				(type default)
			)
			(layer "B.SilkS")
		)
		(fp_line
			(start -1.2954 -0.5842)
			(end -1.2954 0.5842)
			(stroke
				(width 0.1524)
				(type default)
			)
			(layer "B.SilkS")
		)
		(fp_line
			(start 1.2954 0.5842)
			(end 1.2954 -0.5842)
			(stroke
				(width 0.1524)
				(type default)
			)
			(layer "B.SilkS")
		)
		(fp_line
			(start -1.2954 0.5842)
			(end 1.2954 0.5842)
			(stroke
				(width 0.1524)
				(type default)
			)
			(layer "B.SilkS")
		)
		(fp_line
			(start 0.8636 -0.4572)
			(end -0.8636 -0.4572)
			(stroke
				(width 0.1)
				(type default)
			)
			(layer "B.Fab")
		)
		(fp_line
			(start -0.8636 -0.4572)
			(end -0.8636 -0.4064)
			(stroke
				(width 0.1)
				(type default)
			)
			(layer "B.Fab")
		)
		(fp_line
			(start 1.1938 -0.4064)
			(end 0.8636 -0.4064)
			(stroke
				(width 0.1)
				(type default)
			)
			(layer "B.Fab")
		)
		(fp_line
			(start 0.8636 -0.4064)
			(end 0.8636 -0.4572)
			(stroke
				(width 0.1)
				(type default)
			)
			(layer "B.Fab")
		)
		(fp_line
			(start -0.8636 -0.4064)
			(end -1.1938 -0.4064)
			(stroke
				(width 0.1)
				(type default)
			)
			(layer "B.Fab")
		)
		(fp_line
			(start -1.1938 -0.4064)
			(end -1.1938 0.4064)
			(stroke
				(width 0.1)
				(type default)
			)
			(layer "B.Fab")
		)
		(fp_line
			(start 1.1938 0.4064)
			(end 1.1938 -0.4064)
			(stroke
				(width 0.1)
				(type default)
			)
			(layer "B.Fab")
		)
		(fp_line
			(start 0.8636 0.4064)
			(end 1.1938 0.4064)
			(stroke
				(width 0.1)
				(type default)
			)
			(layer "B.Fab")
		)
		(fp_line
			(start -0.8636 0.4064)
			(end -0.8636 0.4572)
			(stroke
				(width 0.1)
				(type default)
			)
			(layer "B.Fab")
		)
		(fp_line
			(start -1.1938 0.4064)
			(end -0.8636 0.4064)
			(stroke
				(width 0.1)
				(type default)
			)
			(layer "B.Fab")
		)
		(fp_line
			(start 0.8636 0.4572)
			(end 0.8636 0.4064)
			(stroke
				(width 0.1)
				(type default)
			)
			(layer "B.Fab")
		)
		(fp_line
			(start -0.8636 0.4572)
			(end 0.8636 0.4572)
			(stroke
				(width 0.1)
				(type default)
			)
			(layer "B.Fab")
		)
		(pad "1" smd rect
			(at 0.7366 0)
			(size 0.7112 0.8128)
			(layers "B.Cu" "B.Mask" "B.Paste")
			(net "P0V8_PEX1")
		)
		(pad "2" smd rect
			(at -0.7366 0)
			(size 0.7112 0.8128)
			(layers "B.Cu" "B.Mask" "B.Paste")
			(net "GND")
		)
	)
	(footprint ""
		(layer "B.Cu")
		(at 183.3499 -299.699934 -90)
		(property "Reference" "C1424"
			(at 0 0 90)
			(layer "B.SilkS")
			(hide yes)
			(effects
				(font
					(size 1.27 1.27)
				)
				(justify mirror)
			)
		)
		(property "Value" ""
			(at 0 0 90)
			(layer "B.Fab")
			(effects
				(font
					(size 1.27 1.27)
				)
				(justify mirror)
			)
		)
		(duplicate_pad_numbers_are_jumpers no)
		(fp_line
			(start -0.299974 0.150114)
			(end 0.299974 0.150114)
			(stroke
				(width 0.1)
				(type default)
			)
			(layer "B.Fab")
		)
		(fp_line
			(start 0.299974 0.150114)
			(end 0.299974 -0.150114)
			(stroke
				(width 0.1)
				(type default)
			)
			(layer "B.Fab")
		)
		(fp_line
			(start -0.299974 -0.150114)
			(end -0.299974 0.150114)
			(stroke
				(width 0.1)
				(type default)
			)
			(layer "B.Fab")
		)
		(fp_line
			(start 0.299974 -0.150114)
			(end -0.299974 -0.150114)
			(stroke
				(width 0.1)
				(type default)
			)
			(layer "B.Fab")
		)
		(pad "1" smd rect
			(at 0.2667 0 90)
			(size 0.3048 0.381)
			(layers "B.Cu" "B.Mask" "B.Paste")
			(net "P0V8_SERDES_VDDA_PEX1")
		)
		(pad "2" smd rect
			(at -0.2667 0 90)
			(size 0.3048 0.381)
			(layers "B.Cu" "B.Mask" "B.Paste")
			(net "GND")
		)
	)
	(footprint ""
		(layer "B.Cu")
		(at 252.0188 -352.8568 180)
		(property "Reference" "R6713"
			(at 0 0 0)
			(layer "B.SilkS")
			(hide yes)
			(effects
				(font
					(size 1.27 1.27)
				)
				(justify mirror)
			)
		)
		(property "Value" ""
			(at 0 0 0)
			(layer "B.Fab")
			(effects
				(font
					(size 1.27 1.27)
				)
				(justify mirror)
			)
		)
		(duplicate_pad_numbers_are_jumpers no)
		(fp_line
			(start 0.7874 0.4064)
			(end 0.7874 -0.4064)
			(stroke
				(width 0.1524)
				(type default)
			)
			(layer "B.SilkS")
		)
		(fp_line
			(start 0.7874 -0.4064)
			(end -0.7874 -0.4064)
			(stroke
				(width 0.1524)
				(type default)
			)
			(layer "B.SilkS")
		)
		(fp_line
			(start -0.7874 0.4064)
			(end 0.7874 0.4064)
			(stroke
				(width 0.1524)
				(type default)
			)
			(layer "B.SilkS")
		)
		(fp_line
			(start -0.7874 -0.4064)
			(end -0.7874 0.4064)
			(stroke
				(width 0.1524)
				(type default)
			)
			(layer "B.SilkS")
		)
		(fp_line
			(start 0.67945 0.3048)
			(end 0.67945 -0.305054)
			(stroke
				(width 0.1)
				(type default)
			)
			(layer "B.Fab")
		)
		(fp_line
			(start 0.67945 -0.305054)
			(end 0.12065 -0.305054)
			(stroke
				(width 0.1)
				(type default)
			)
			(layer "B.Fab")
		)
		(fp_line
			(start 0.12065 0.3048)
			(end 0.67945 0.3048)
			(stroke
				(width 0.1)
				(type default)
			)
			(layer "B.Fab")
		)
		(fp_line
			(start 0.12065 0.2794)
			(end 0.12065 0.3048)
			(stroke
				(width 0.1)
				(type default)
			)
			(layer "B.Fab")
		)
		(fp_line
			(start 0.12065 -0.2794)
			(end -0.12065 -0.2794)
			(stroke
				(width 0.1)
				(type default)
			)
			(layer "B.Fab")
		)
		(fp_line
			(start 0.12065 -0.305054)
			(end 0.12065 -0.2794)
			(stroke
				(width 0.1)
				(type default)
			)
			(layer "B.Fab")
		)
		(fp_line
			(start -0.120396 0.3048)
			(end -0.120396 0.2794)
			(stroke
				(width 0.1)
				(type default)
			)
			(layer "B.Fab")
		)
		(fp_line
			(start -0.120396 0.2794)
			(end 0.12065 0.2794)
			(stroke
				(width 0.1)
				(type default)
			)
			(layer "B.Fab")
		)
		(fp_line
			(start -0.12065 -0.2794)
			(end -0.12065 -0.3048)
			(stroke
				(width 0.1)
				(type default)
			)
			(layer "B.Fab")
		)
		(fp_line
			(start -0.12065 -0.3048)
			(end -0.67945 -0.3048)
			(stroke
				(width 0.1)
				(type default)
			)
			(layer "B.Fab")
		)
		(fp_line
			(start -0.67945 0.3048)
			(end -0.120396 0.3048)
			(stroke
				(width 0.1)
				(type default)
			)
			(layer "B.Fab")
		)
		(fp_line
			(start -0.67945 -0.3048)
			(end -0.67945 0.3048)
			(stroke
				(width 0.1)
				(type default)
			)
			(layer "B.Fab")
		)
		(pad "1" smd circle
			(at 0.40005 0)
			(size 0 0)
			(layers "B.Cu" "B.Mask" "B.Paste")
			(net "HSC_TYPE_ADC")
		)
		(pad "2" smd circle
			(at -0.40005 0)
			(size 0 0)
			(layers "B.Cu" "B.Mask" "B.Paste")
			(net "HSC_TYPE_ADC_R")
		)
	)
	(footprint ""
		(layer "B.Cu")
		(at 210.596734 -215.642444)
		(property "Reference" "R5478"
			(at 0 0 0)
			(layer "B.SilkS")
			(hide yes)
			(effects
				(font
					(size 1.27 1.27)
				)
				(justify mirror)
			)
		)
		(property "Value" ""
			(at 0 0 0)
			(layer "B.Fab")
			(effects
				(font
					(size 1.27 1.27)
				)
				(justify mirror)
			)
		)
		(duplicate_pad_numbers_are_jumpers no)
		(fp_line
			(start -0.7874 -0.4064)
			(end -0.7874 0.4064)
			(stroke
				(width 0.1524)
				(type default)
			)
			(layer "B.SilkS")
		)
		(fp_line
			(start -0.7874 0.4064)
			(end 0.7874 0.4064)
			(stroke
				(width 0.1524)
				(type default)
			)
			(layer "B.SilkS")
		)
		(fp_line
			(start 0.7874 -0.4064)
			(end -0.7874 -0.4064)
			(stroke
				(width 0.1524)
				(type default)
			)
			(layer "B.SilkS")
		)
		(fp_line
			(start 0.7874 0.4064)
			(end 0.7874 -0.4064)
			(stroke
				(width 0.1524)
				(type default)
			)
			(layer "B.SilkS")
		)
		(fp_line
			(start -0.67945 -0.3048)
			(end -0.67945 0.3048)
			(stroke
				(width 0.1)
				(type default)
			)
			(layer "B.Fab")
		)
		(fp_line
			(start -0.67945 0.3048)
			(end -0.120396 0.3048)
			(stroke
				(width 0.1)
				(type default)
			)
			(layer "B.Fab")
		)
		(fp_line
			(start -0.12065 -0.3048)
			(end -0.67945 -0.3048)
			(stroke
				(width 0.1)
				(type default)
			)
			(layer "B.Fab")
		)
		(fp_line
			(start -0.12065 -0.2794)
			(end -0.12065 -0.3048)
			(stroke
				(width 0.1)
				(type default)
			)
			(layer "B.Fab")
		)
		(fp_line
			(start -0.120396 0.2794)
			(end 0.12065 0.2794)
			(stroke
				(width 0.1)
				(type default)
			)
			(layer "B.Fab")
		)
		(fp_line
			(start -0.120396 0.3048)
			(end -0.120396 0.2794)
			(stroke
				(width 0.1)
				(type default)
			)
			(layer "B.Fab")
		)
		(fp_line
			(start 0.12065 -0.305054)
			(end 0.12065 -0.2794)
			(stroke
				(width 0.1)
				(type default)
			)
			(layer "B.Fab")
		)
		(fp_line
			(start 0.12065 -0.2794)
			(end -0.12065 -0.2794)
			(stroke
				(width 0.1)
				(type default)
			)
			(layer "B.Fab")
		)
		(fp_line
			(start 0.12065 0.2794)
			(end 0.12065 0.3048)
			(stroke
				(width 0.1)
				(type default)
			)
			(layer "B.Fab")
		)
		(fp_line
			(start 0.12065 0.3048)
			(end 0.67945 0.3048)
			(stroke
				(width 0.1)
				(type default)
			)
			(layer "B.Fab")
		)
		(fp_line
			(start 0.67945 -0.305054)
			(end 0.12065 -0.305054)
			(stroke
				(width 0.1)
				(type default)
			)
			(layer "B.Fab")
		)
		(fp_line
			(start 0.67945 0.3048)
			(end 0.67945 -0.305054)
			(stroke
				(width 0.1)
				(type default)
			)
			(layer "B.Fab")
		)
		(pad "1" smd circle
			(at 0.40005 0 180)
			(size 0 0)
			(layers "B.Cu" "B.Mask" "B.Paste")
			(net "USB_DEBUG_RST_BTN_N")
		)
		(pad "2" smd circle
			(at -0.40005 0 180)
			(size 0 0)
			(layers "B.Cu" "B.Mask" "B.Paste")
			(net "USB_DEBUG_RST_BTN_R_N")
		)
	)
	(footprint ""
		(layer "B.Cu")
		(at 202.633072 -364.80496)
		(property "Reference" "PR6"
			(at 0 0 0)
			(layer "B.SilkS")
			(hide yes)
			(effects
				(font
					(size 1.27 1.27)
				)
				(justify mirror)
			)
		)
		(property "Value" ""
			(at 0 0 0)
			(layer "B.Fab")
			(effects
				(font
					(size 1.27 1.27)
				)
				(justify mirror)
			)
		)
		(duplicate_pad_numbers_are_jumpers no)
		(fp_line
			(start -0.7874 -0.4064)
			(end -0.7874 0.4064)
			(stroke
				(width 0.1524)
				(type default)
			)
			(layer "B.SilkS")
		)
		(fp_line
			(start -0.7874 0.4064)
			(end 0.7874 0.4064)
			(stroke
				(width 0.1524)
				(type default)
			)
			(layer "B.SilkS")
		)
		(fp_line
			(start 0.7874 -0.4064)
			(end -0.7874 -0.4064)
			(stroke
				(width 0.1524)
				(type default)
			)
			(layer "B.SilkS")
		)
		(fp_line
			(start 0.7874 0.4064)
			(end 0.7874 -0.4064)
			(stroke
				(width 0.1524)
				(type default)
			)
			(layer "B.SilkS")
		)
		(fp_line
			(start -0.67945 -0.3048)
			(end -0.67945 0.3048)
			(stroke
				(width 0.1)
				(type default)
			)
			(layer "B.Fab")
		)
		(fp_line
			(start -0.67945 0.3048)
			(end -0.120396 0.3048)
			(stroke
				(width 0.1)
				(type default)
			)
			(layer "B.Fab")
		)
		(fp_line
			(start -0.12065 -0.3048)
			(end -0.67945 -0.3048)
			(stroke
				(width 0.1)
				(type default)
			)
			(layer "B.Fab")
		)
		(fp_line
			(start -0.12065 -0.2794)
			(end -0.12065 -0.3048)
			(stroke
				(width 0.1)
				(type default)
			)
			(layer "B.Fab")
		)
		(fp_line
			(start -0.120396 0.2794)
			(end 0.12065 0.2794)
			(stroke
				(width 0.1)
				(type default)
			)
			(layer "B.Fab")
		)
		(fp_line
			(start -0.120396 0.3048)
			(end -0.120396 0.2794)
			(stroke
				(width 0.1)
				(type default)
			)
			(layer "B.Fab")
		)
		(fp_line
			(start 0.12065 -0.305054)
			(end 0.12065 -0.2794)
			(stroke
				(width 0.1)
				(type default)
			)
			(layer "B.Fab")
		)
		(fp_line
			(start 0.12065 -0.2794)
			(end -0.12065 -0.2794)
			(stroke
				(width 0.1)
				(type default)
			)
			(layer "B.Fab")
		)
		(fp_line
			(start 0.12065 0.2794)
			(end 0.12065 0.3048)
			(stroke
				(width 0.1)
				(type default)
			)
			(layer "B.Fab")
		)
		(fp_line
			(start 0.12065 0.3048)
			(end 0.67945 0.3048)
			(stroke
				(width 0.1)
				(type default)
			)
			(layer "B.Fab")
		)
		(fp_line
			(start 0.67945 -0.305054)
			(end 0.12065 -0.305054)
			(stroke
				(width 0.1)
				(type default)
			)
			(layer "B.Fab")
		)
		(fp_line
			(start 0.67945 0.3048)
			(end 0.67945 -0.305054)
			(stroke
				(width 0.1)
				(type default)
			)
			(layer "B.Fab")
		)
		(pad "1" smd circle
			(at 0.40005 0 180)
			(size 0 0)
			(layers "B.Cu" "B.Mask" "B.Paste")
			(net "HSC_VOSEN")
		)
		(pad "2" smd circle
			(at -0.40005 0 180)
			(size 0 0)
			(layers "B.Cu" "B.Mask" "B.Paste")
			(net "AGND_HSC")
		)
	)
	(footprint ""
		(layer "B.Cu")
		(at 180.975 -286.399732 90)
		(property "Reference" "C3142"
			(at 0 0 90)
			(layer "B.SilkS")
			(hide yes)
			(effects
				(font
					(size 1.27 1.27)
				)
				(justify mirror)
			)
		)
		(property "Value" ""
			(at 0 0 90)
			(layer "B.Fab")
			(effects
				(font
					(size 1.27 1.27)
				)
				(justify mirror)
			)
		)
		(duplicate_pad_numbers_are_jumpers no)
		(fp_line
			(start 0.299974 -0.150114)
			(end -0.299974 -0.150114)
			(stroke
				(width 0.1)
				(type default)
			)
			(layer "B.Fab")
		)
		(fp_line
			(start -0.299974 -0.150114)
			(end -0.299974 0.150114)
			(stroke
				(width 0.1)
				(type default)
			)
			(layer "B.Fab")
		)
		(fp_line
			(start 0.299974 0.150114)
			(end 0.299974 -0.150114)
			(stroke
				(width 0.1)
				(type default)
			)
			(layer "B.Fab")
		)
		(fp_line
			(start -0.299974 0.150114)
			(end 0.299974 0.150114)
			(stroke
				(width 0.1)
				(type default)
			)
			(layer "B.Fab")
		)
		(pad "1" smd rect
			(at 0.2667 0 270)
			(size 0.3048 0.381)
			(layers "B.Cu" "B.Mask" "B.Paste")
			(net "P1V25_SERDES_VDDPLL_PEX1")
		)
		(pad "2" smd rect
			(at -0.2667 0 270)
			(size 0.3048 0.381)
			(layers "B.Cu" "B.Mask" "B.Paste")
			(net "GND")
		)
	)
)
